(kicad_pcb
	(version 20260206)
	(generator "pcbnew")
	(generator_version "10.0")
	(general
		(thickness 1.6)
		(legacy_teardrops no)
	)
	(paper "A4")
	(title_block
		(title "03242023_DA0F0TMBIJ0_F0T_Motherboard_J_brd_V01_OCP.brd")
		(comment 1 "Grand Teton / footprints 334-339 of 6105")
	)
	(layers
		(0 "F.Cu" signal "TOP")
		(4 "In1.Cu" signal "GND")
		(6 "In2.Cu" signal "IN1")
		(8 "In3.Cu" signal "GND1")
		(10 "In4.Cu" signal "IN2")
		(12 "In5.Cu" signal "GND2")
		(14 "In6.Cu" signal "IN3")
		(16 "In7.Cu" signal "GND3")
		(18 "In8.Cu" signal "VCC")
		(20 "In9.Cu" signal "VCC1")
		(22 "In10.Cu" signal "GND4")
		(24 "In11.Cu" signal "IN4")
		(26 "In12.Cu" signal "GND5")
		(28 "In13.Cu" signal "IN5")
		(30 "In14.Cu" signal "GND6")
		(32 "In15.Cu" signal "IN6")
		(34 "In16.Cu" signal "GND7")
		(2 "B.Cu" signal "BOTTOM")
		(9 "F.Adhes" user "F.Adhesive")
		(11 "B.Adhes" user "B.Adhesive")
		(13 "F.Paste" user "Package Geometry/Pastemask Top")
		(15 "B.Paste" user "Package Geometry/Pastemask Bottom")
		(5 "F.SilkS" user "Ref Des/Silkscreen Top")
		(7 "B.SilkS" user "Ref Des/Silkscreen Bottom")
		(1 "F.Mask" user "Board Geometry/Soldermask Top")
		(3 "B.Mask" user "Board Geometry/Soldermask Bottom")
		(17 "Dwgs.User" user "User.Drawings")
		(19 "Cmts.User" user "User.Comments")
		(21 "Eco1.User" user "User.Eco1")
		(23 "Eco2.User" user "User.Eco2")
		(25 "Edge.Cuts" user "Board Geometry/Outline")
		(27 "Margin" user)
		(31 "F.CrtYd" user "Package Geometry/Place Bound Top")
		(29 "B.CrtYd" user "Package Geometry/Place Bound Bottom")
		(35 "F.Fab" user "Ref Des/Assembly Top")
		(33 "B.Fab" user "Ref Des/Assembly Bottom")
	)
	(footprint ""
		(layer "F.Cu")
		(at 44.169584 -107.031282)
		(property "Reference" "R1785"
			(at 0 0 0)
			(layer "F.SilkS")
			(hide yes)
			(effects
				(font
					(size 1.27 1.27)
				)
			)
		)
		(property "Value" ""
			(at 0 0 0)
			(layer "F.Fab")
			(effects
				(font
					(size 1.27 1.27)
				)
			)
		)
		(duplicate_pad_numbers_are_jumpers no)
		(fp_line
			(start -0.7874 -0.4064)
			(end 0.7874 -0.4064)
			(stroke
				(width 0.1524)
				(type default)
			)
			(layer "F.SilkS")
		)
		(fp_line
			(start -0.7874 0.4064)
			(end -0.7874 -0.4064)
			(stroke
				(width 0.1524)
				(type default)
			)
			(layer "F.SilkS")
		)
		(fp_line
			(start 0.7874 -0.4064)
			(end 0.7874 0.4064)
			(stroke
				(width 0.1524)
				(type default)
			)
			(layer "F.SilkS")
		)
		(fp_line
			(start 0.7874 0.4064)
			(end -0.7874 0.4064)
			(stroke
				(width 0.1524)
				(type default)
			)
			(layer "F.SilkS")
		)
		(fp_line
			(start -0.67945 -0.305054)
			(end -0.12065 -0.305054)
			(stroke
				(width 0.1)
				(type default)
			)
			(layer "F.Fab")
		)
		(fp_line
			(start -0.67945 0.3048)
			(end -0.67945 -0.305054)
			(stroke
				(width 0.1)
				(type default)
			)
			(layer "F.Fab")
		)
		(fp_line
			(start -0.12065 -0.305054)
			(end -0.12065 -0.2794)
			(stroke
				(width 0.1)
				(type default)
			)
			(layer "F.Fab")
		)
		(fp_line
			(start -0.12065 -0.2794)
			(end 0.12065 -0.2794)
			(stroke
				(width 0.1)
				(type default)
			)
			(layer "F.Fab")
		)
		(fp_line
			(start -0.12065 0.2794)
			(end -0.12065 0.3048)
			(stroke
				(width 0.1)
				(type default)
			)
			(layer "F.Fab")
		)
		(fp_line
			(start -0.12065 0.3048)
			(end -0.67945 0.3048)
			(stroke
				(width 0.1)
				(type default)
			)
			(layer "F.Fab")
		)
		(fp_line
			(start 0.120396 0.2794)
			(end -0.12065 0.2794)
			(stroke
				(width 0.1)
				(type default)
			)
			(layer "F.Fab")
		)
		(fp_line
			(start 0.120396 0.3048)
			(end 0.120396 0.2794)
			(stroke
				(width 0.1)
				(type default)
			)
			(layer "F.Fab")
		)
		(fp_line
			(start 0.12065 -0.3048)
			(end 0.67945 -0.3048)
			(stroke
				(width 0.1)
				(type default)
			)
			(layer "F.Fab")
		)
		(fp_line
			(start 0.12065 -0.2794)
			(end 0.12065 -0.3048)
			(stroke
				(width 0.1)
				(type default)
			)
			(layer "F.Fab")
		)
		(fp_line
			(start 0.67945 -0.3048)
			(end 0.67945 0.3048)
			(stroke
				(width 0.1)
				(type default)
			)
			(layer "F.Fab")
		)
		(fp_line
			(start 0.67945 0.3048)
			(end 0.120396 0.3048)
			(stroke
				(width 0.1)
				(type default)
			)
			(layer "F.Fab")
		)
		(pad "1" smd circle
			(at -0.40005 0)
			(size 0 0)
			(layers "F.Cu" "F.Mask" "F.Paste")
			(net "P3V3_AUX_ADC")
		)
		(pad "2" smd circle
			(at 0.40005 0)
			(size 0 0)
			(layers "F.Cu" "F.Mask" "F.Paste")
			(net "GND")
		)
	)
	(footprint ""
		(layer "F.Cu")
		(at 447.687192 -21.236178 180)
		(property "Reference" "PR5484"
			(at 0 0 180)
			(layer "F.SilkS")
			(hide yes)
			(effects
				(font
					(size 1.27 1.27)
				)
			)
		)
		(property "Value" ""
			(at 0 0 180)
			(layer "F.Fab")
			(effects
				(font
					(size 1.27 1.27)
				)
			)
		)
		(duplicate_pad_numbers_are_jumpers no)
		(fp_line
			(start 0.7874 0.4064)
			(end -0.7874 0.4064)
			(stroke
				(width 0.1524)
				(type default)
			)
			(layer "F.SilkS")
		)
		(fp_line
			(start 0.7874 -0.4064)
			(end 0.7874 0.4064)
			(stroke
				(width 0.1524)
				(type default)
			)
			(layer "F.SilkS")
		)
		(fp_line
			(start -0.7874 0.4064)
			(end -0.7874 -0.4064)
			(stroke
				(width 0.1524)
				(type default)
			)
			(layer "F.SilkS")
		)
		(fp_line
			(start -0.7874 -0.4064)
			(end 0.7874 -0.4064)
			(stroke
				(width 0.1524)
				(type default)
			)
			(layer "F.SilkS")
		)
		(fp_line
			(start 0.67945 0.3048)
			(end 0.120396 0.3048)
			(stroke
				(width 0.1)
				(type default)
			)
			(layer "F.Fab")
		)
		(fp_line
			(start 0.67945 -0.3048)
			(end 0.67945 0.3048)
			(stroke
				(width 0.1)
				(type default)
			)
			(layer "F.Fab")
		)
		(fp_line
			(start 0.12065 -0.2794)
			(end 0.12065 -0.3048)
			(stroke
				(width 0.1)
				(type default)
			)
			(layer "F.Fab")
		)
		(fp_line
			(start 0.12065 -0.3048)
			(end 0.67945 -0.3048)
			(stroke
				(width 0.1)
				(type default)
			)
			(layer "F.Fab")
		)
		(fp_line
			(start 0.120396 0.3048)
			(end 0.120396 0.2794)
			(stroke
				(width 0.1)
				(type default)
			)
			(layer "F.Fab")
		)
		(fp_line
			(start 0.120396 0.2794)
			(end -0.12065 0.2794)
			(stroke
				(width 0.1)
				(type default)
			)
			(layer "F.Fab")
		)
		(fp_line
			(start -0.12065 0.3048)
			(end -0.67945 0.3048)
			(stroke
				(width 0.1)
				(type default)
			)
			(layer "F.Fab")
		)
		(fp_line
			(start -0.12065 0.2794)
			(end -0.12065 0.3048)
			(stroke
				(width 0.1)
				(type default)
			)
			(layer "F.Fab")
		)
		(fp_line
			(start -0.12065 -0.2794)
			(end 0.12065 -0.2794)
			(stroke
				(width 0.1)
				(type default)
			)
			(layer "F.Fab")
		)
		(fp_line
			(start -0.12065 -0.305054)
			(end -0.12065 -0.2794)
			(stroke
				(width 0.1)
				(type default)
			)
			(layer "F.Fab")
		)
		(fp_line
			(start -0.67945 0.3048)
			(end -0.67945 -0.305054)
			(stroke
				(width 0.1)
				(type default)
			)
			(layer "F.Fab")
		)
		(fp_line
			(start -0.67945 -0.305054)
			(end -0.12065 -0.305054)
			(stroke
				(width 0.1)
				(type default)
			)
			(layer "F.Fab")
		)
		(pad "1" smd circle
			(at -0.40005 0 180)
			(size 0 0)
			(layers "F.Cu" "F.Mask" "F.Paste")
			(net "P12V_OCP_CB_1")
		)
		(pad "2" smd circle
			(at 0.40005 0 180)
			(size 0 0)
			(layers "F.Cu" "F.Mask" "F.Paste")
			(net "GND")
		)
	)
	(footprint ""
		(layer "F.Cu")
		(at 366.48263 -244.03177 90)
		(property "Reference" "C1017"
			(at 0 0 90)
			(layer "F.SilkS")
			(hide yes)
			(effects
				(font
					(size 1.27 1.27)
				)
			)
		)
		(property "Value" ""
			(at 0 0 90)
			(layer "F.Fab")
			(effects
				(font
					(size 1.27 1.27)
				)
			)
		)
		(duplicate_pad_numbers_are_jumpers no)
		(fp_line
			(start 0.7874 -0.4064)
			(end 0.7874 0.4064)
			(stroke
				(width 0.1524)
				(type default)
			)
			(layer "F.SilkS")
		)
		(fp_line
			(start -0.7874 -0.4064)
			(end 0.7874 -0.4064)
			(stroke
				(width 0.1524)
				(type default)
			)
			(layer "F.SilkS")
		)
		(fp_line
			(start 0.7874 0.4064)
			(end -0.7874 0.4064)
			(stroke
				(width 0.1524)
				(type default)
			)
			(layer "F.SilkS")
		)
		(fp_line
			(start -0.7874 0.4064)
			(end -0.7874 -0.4064)
			(stroke
				(width 0.1524)
				(type default)
			)
			(layer "F.SilkS")
		)
		(fp_line
			(start -0.12065 -0.305054)
			(end -0.12065 -0.2794)
			(stroke
				(width 0.1)
				(type default)
			)
			(layer "F.Fab")
		)
		(fp_line
			(start -0.67945 -0.305054)
			(end -0.12065 -0.305054)
			(stroke
				(width 0.1)
				(type default)
			)
			(layer "F.Fab")
		)
		(fp_line
			(start 0.67945 -0.3048)
			(end 0.67945 0.3048)
			(stroke
				(width 0.1)
				(type default)
			)
			(layer "F.Fab")
		)
		(fp_line
			(start 0.12065 -0.3048)
			(end 0.67945 -0.3048)
			(stroke
				(width 0.1)
				(type default)
			)
			(layer "F.Fab")
		)
		(fp_line
			(start 0.12065 -0.2794)
			(end 0.12065 -0.3048)
			(stroke
				(width 0.1)
				(type default)
			)
			(layer "F.Fab")
		)
		(fp_line
			(start -0.12065 -0.2794)
			(end 0.12065 -0.2794)
			(stroke
				(width 0.1)
				(type default)
			)
			(layer "F.Fab")
		)
		(fp_line
			(start 0.120396 0.2794)
			(end -0.12065 0.2794)
			(stroke
				(width 0.1)
				(type default)
			)
			(layer "F.Fab")
		)
		(fp_line
			(start -0.12065 0.2794)
			(end -0.12065 0.3048)
			(stroke
				(width 0.1)
				(type default)
			)
			(layer "F.Fab")
		)
		(fp_line
			(start 0.67945 0.3048)
			(end 0.120396 0.3048)
			(stroke
				(width 0.1)
				(type default)
			)
			(layer "F.Fab")
		)
		(fp_line
			(start 0.120396 0.3048)
			(end 0.120396 0.2794)
			(stroke
				(width 0.1)
				(type default)
			)
			(layer "F.Fab")
		)
		(fp_line
			(start -0.12065 0.3048)
			(end -0.67945 0.3048)
			(stroke
				(width 0.1)
				(type default)
			)
			(layer "F.Fab")
		)
		(fp_line
			(start -0.67945 0.3048)
			(end -0.67945 -0.305054)
			(stroke
				(width 0.1)
				(type default)
			)
			(layer "F.Fab")
		)
		(pad "1" smd circle
			(at -0.40005 0 90)
			(size 0 0)
			(layers "F.Cu" "F.Mask" "F.Paste")
			(net "PVCCIN_CPU0")
		)
		(pad "2" smd circle
			(at 0.40005 0 90)
			(size 0 0)
			(layers "F.Cu" "F.Mask" "F.Paste")
			(net "GND")
		)
	)
	(footprint ""
		(layer "F.Cu")
		(at 158.33471 -81.90865 -90)
		(property "Reference" "R3225"
			(at 0 0 270)
			(layer "F.SilkS")
			(hide yes)
			(effects
				(font
					(size 1.27 1.27)
				)
			)
		)
		(property "Value" ""
			(at 0 0 270)
			(layer "F.Fab")
			(effects
				(font
					(size 1.27 1.27)
				)
			)
		)
		(duplicate_pad_numbers_are_jumpers no)
		(fp_line
			(start -0.7874 0.4064)
			(end -0.7874 -0.4064)
			(stroke
				(width 0.1524)
				(type default)
			)
			(layer "F.SilkS")
		)
		(fp_line
			(start 0.7874 0.4064)
			(end -0.7874 0.4064)
			(stroke
				(width 0.1524)
				(type default)
			)
			(layer "F.SilkS")
		)
		(fp_line
			(start -0.7874 -0.4064)
			(end 0.7874 -0.4064)
			(stroke
				(width 0.1524)
				(type default)
			)
			(layer "F.SilkS")
		)
		(fp_line
			(start 0.7874 -0.4064)
			(end 0.7874 0.4064)
			(stroke
				(width 0.1524)
				(type default)
			)
			(layer "F.SilkS")
		)
		(fp_line
			(start -0.67945 0.3048)
			(end -0.67945 -0.305054)
			(stroke
				(width 0.1)
				(type default)
			)
			(layer "F.Fab")
		)
		(fp_line
			(start -0.12065 0.3048)
			(end -0.67945 0.3048)
			(stroke
				(width 0.1)
				(type default)
			)
			(layer "F.Fab")
		)
		(fp_line
			(start 0.120396 0.3048)
			(end 0.120396 0.2794)
			(stroke
				(width 0.1)
				(type default)
			)
			(layer "F.Fab")
		)
		(fp_line
			(start 0.67945 0.3048)
			(end 0.120396 0.3048)
			(stroke
				(width 0.1)
				(type default)
			)
			(layer "F.Fab")
		)
		(fp_line
			(start -0.12065 0.2794)
			(end -0.12065 0.3048)
			(stroke
				(width 0.1)
				(type default)
			)
			(layer "F.Fab")
		)
		(fp_line
			(start 0.120396 0.2794)
			(end -0.12065 0.2794)
			(stroke
				(width 0.1)
				(type default)
			)
			(layer "F.Fab")
		)
		(fp_line
			(start -0.12065 -0.2794)
			(end 0.12065 -0.2794)
			(stroke
				(width 0.1)
				(type default)
			)
			(layer "F.Fab")
		)
		(fp_line
			(start 0.12065 -0.2794)
			(end 0.12065 -0.3048)
			(stroke
				(width 0.1)
				(type default)
			)
			(layer "F.Fab")
		)
		(fp_line
			(start 0.12065 -0.3048)
			(end 0.67945 -0.3048)
			(stroke
				(width 0.1)
				(type default)
			)
			(layer "F.Fab")
		)
		(fp_line
			(start 0.67945 -0.3048)
			(end 0.67945 0.3048)
			(stroke
				(width 0.1)
				(type default)
			)
			(layer "F.Fab")
		)
		(fp_line
			(start -0.67945 -0.305054)
			(end -0.12065 -0.305054)
			(stroke
				(width 0.1)
				(type default)
			)
			(layer "F.Fab")
		)
		(fp_line
			(start -0.12065 -0.305054)
			(end -0.12065 -0.2794)
			(stroke
				(width 0.1)
				(type default)
			)
			(layer "F.Fab")
		)
		(pad "1" smd circle
			(at -0.40005 0 270)
			(size 0 0)
			(layers "F.Cu" "F.Mask" "F.Paste")
			(net "SMB_S3M_CPU1_PIROM_3V3AUX_SDA")
		)
		(pad "2" smd circle
			(at 0.40005 0 270)
			(size 0 0)
			(layers "F.Cu" "F.Mask" "F.Paste")
			(net "P3V3_AUX")
		)
	)
	(footprint ""
		(layer "F.Cu")
		(at 94.201996 -338.298282 -90)
		(property "Reference" "PC1339"
			(at 0 0 270)
			(layer "F.SilkS")
			(hide yes)
			(effects
				(font
					(size 1.27 1.27)
				)
			)
		)
		(property "Value" ""
			(at 0 0 270)
			(layer "F.Fab")
			(effects
				(font
					(size 1.27 1.27)
				)
			)
		)
		(duplicate_pad_numbers_are_jumpers no)
		(fp_line
			(start -0.7874 0.4064)
			(end -0.7874 -0.4064)
			(stroke
				(width 0.1524)
				(type default)
			)
			(layer "F.SilkS")
		)
		(fp_line
			(start 0.7874 0.4064)
			(end -0.7874 0.4064)
			(stroke
				(width 0.1524)
				(type default)
			)
			(layer "F.SilkS")
		)
		(fp_line
			(start -0.7874 -0.4064)
			(end 0.7874 -0.4064)
			(stroke
				(width 0.1524)
				(type default)
			)
			(layer "F.SilkS")
		)
		(fp_line
			(start 0.7874 -0.4064)
			(end 0.7874 0.4064)
			(stroke
				(width 0.1524)
				(type default)
			)
			(layer "F.SilkS")
		)
		(fp_line
			(start -0.67945 0.3048)
			(end -0.67945 -0.305054)
			(stroke
				(width 0.1)
				(type default)
			)
			(layer "F.Fab")
		)
		(fp_line
			(start -0.12065 0.3048)
			(end -0.67945 0.3048)
			(stroke
				(width 0.1)
				(type default)
			)
			(layer "F.Fab")
		)
		(fp_line
			(start 0.120396 0.3048)
			(end 0.120396 0.2794)
			(stroke
				(width 0.1)
				(type default)
			)
			(layer "F.Fab")
		)
		(fp_line
			(start 0.67945 0.3048)
			(end 0.120396 0.3048)
			(stroke
				(width 0.1)
				(type default)
			)
			(layer "F.Fab")
		)
		(fp_line
			(start -0.12065 0.2794)
			(end -0.12065 0.3048)
			(stroke
				(width 0.1)
				(type default)
			)
			(layer "F.Fab")
		)
		(fp_line
			(start 0.120396 0.2794)
			(end -0.12065 0.2794)
			(stroke
				(width 0.1)
				(type default)
			)
			(layer "F.Fab")
		)
		(fp_line
			(start -0.12065 -0.2794)
			(end 0.12065 -0.2794)
			(stroke
				(width 0.1)
				(type default)
			)
			(layer "F.Fab")
		)
		(fp_line
			(start 0.12065 -0.2794)
			(end 0.12065 -0.3048)
			(stroke
				(width 0.1)
				(type default)
			)
			(layer "F.Fab")
		)
		(fp_line
			(start 0.12065 -0.3048)
			(end 0.67945 -0.3048)
			(stroke
				(width 0.1)
				(type default)
			)
			(layer "F.Fab")
		)
		(fp_line
			(start 0.67945 -0.3048)
			(end 0.67945 0.3048)
			(stroke
				(width 0.1)
				(type default)
			)
			(layer "F.Fab")
		)
		(fp_line
			(start -0.67945 -0.305054)
			(end -0.12065 -0.305054)
			(stroke
				(width 0.1)
				(type default)
			)
			(layer "F.Fab")
		)
		(fp_line
			(start -0.12065 -0.305054)
			(end -0.12065 -0.2794)
			(stroke
				(width 0.1)
				(type default)
			)
			(layer "F.Fab")
		)
		(pad "1" smd circle
			(at -0.40005 0 270)
			(size 0 0)
			(layers "F.Cu" "F.Mask" "F.Paste")
			(net "GND")
		)
		(pad "2" smd circle
			(at 0.40005 0 270)
			(size 0 0)
			(layers "F.Cu" "F.Mask" "F.Paste")
			(net "PVCCIN_CPU1_VREF")
		)
	)
	(footprint ""
		(layer "F.Cu")
		(at 209.74558 -127.528828)
		(property "Reference" "R1695"
			(at 0 0 0)
			(layer "F.SilkS")
			(hide yes)
			(effects
				(font
					(size 1.27 1.27)
				)
			)
		)
		(property "Value" ""
			(at 0 0 0)
			(layer "F.Fab")
			(effects
				(font
					(size 1.27 1.27)
				)
			)
		)
		(duplicate_pad_numbers_are_jumpers no)
		(fp_line
			(start -0.7874 -0.4064)
			(end 0.7874 -0.4064)
			(stroke
				(width 0.1524)
				(type default)
			)
			(layer "F.SilkS")
		)
		(fp_line
			(start -0.7874 0.4064)
			(end -0.7874 -0.4064)
			(stroke
				(width 0.1524)
				(type default)
			)
			(layer "F.SilkS")
		)
		(fp_line
			(start 0.7874 -0.4064)
			(end 0.7874 0.4064)
			(stroke
				(width 0.1524)
				(type default)
			)
			(layer "F.SilkS")
		)
		(fp_line
			(start 0.7874 0.4064)
			(end -0.7874 0.4064)
			(stroke
				(width 0.1524)
				(type default)
			)
			(layer "F.SilkS")
		)
		(fp_line
			(start -0.67945 -0.305054)
			(end -0.12065 -0.305054)
			(stroke
				(width 0.1)
				(type default)
			)
			(layer "F.Fab")
		)
		(fp_line
			(start -0.67945 0.3048)
			(end -0.67945 -0.305054)
			(stroke
				(width 0.1)
				(type default)
			)
			(layer "F.Fab")
		)
		(fp_line
			(start -0.12065 -0.305054)
			(end -0.12065 -0.2794)
			(stroke
				(width 0.1)
				(type default)
			)
			(layer "F.Fab")
		)
		(fp_line
			(start -0.12065 -0.2794)
			(end 0.12065 -0.2794)
			(stroke
				(width 0.1)
				(type default)
			)
			(layer "F.Fab")
		)
		(fp_line
			(start -0.12065 0.2794)
			(end -0.12065 0.3048)
			(stroke
				(width 0.1)
				(type default)
			)
			(layer "F.Fab")
		)
		(fp_line
			(start -0.12065 0.3048)
			(end -0.67945 0.3048)
			(stroke
				(width 0.1)
				(type default)
			)
			(layer "F.Fab")
		)
		(fp_line
			(start 0.120396 0.2794)
			(end -0.12065 0.2794)
			(stroke
				(width 0.1)
				(type default)
			)
			(layer "F.Fab")
		)
		(fp_line
			(start 0.120396 0.3048)
			(end 0.120396 0.2794)
			(stroke
				(width 0.1)
				(type default)
			)
			(layer "F.Fab")
		)
		(fp_line
			(start 0.12065 -0.3048)
			(end 0.67945 -0.3048)
			(stroke
				(width 0.1)
				(type default)
			)
			(layer "F.Fab")
		)
		(fp_line
			(start 0.12065 -0.2794)
			(end 0.12065 -0.3048)
			(stroke
				(width 0.1)
				(type default)
			)
			(layer "F.Fab")
		)
		(fp_line
			(start 0.67945 -0.3048)
			(end 0.67945 0.3048)
			(stroke
				(width 0.1)
				(type default)
			)
			(layer "F.Fab")
		)
		(fp_line
			(start 0.67945 0.3048)
			(end 0.120396 0.3048)
			(stroke
				(width 0.1)
				(type default)
			)
			(layer "F.Fab")
		)
		(pad "1" smd circle
			(at -0.40005 0)
			(size 0 0)
			(layers "F.Cu" "F.Mask" "F.Paste")
			(net "PWRGD_DSW_PWROK")
		)
		(pad "2" smd circle
			(at 0.40005 0)
			(size 0 0)
			(layers "F.Cu" "F.Mask" "F.Paste")
			(net "RST_RSMRST_PCH_N")
		)
	)
)
